(kicad_pcb
	(version 20260206)
	(generator "pcbnew")
	(generator_version "10.0")
	(general
		(thickness 1.6)
		(legacy_teardrops no)
	)
	(paper "A4")
	(title_block
		(title "peb — Lightning_PEB_BRD.brd")
		(comment 1 "Lightning (Wiwynn / Facebook NVMe JBOF) / footprints 2436-2442 of 2563")
	)
	(layers
		(0 "F.Cu" signal "TOP")
		(4 "In1.Cu" signal "L2GND")
		(6 "In2.Cu" signal "L3")
		(8 "In3.Cu" signal "L4VCC")
		(10 "In4.Cu" signal "L5VCC")
		(12 "In5.Cu" signal "L6")
		(14 "In6.Cu" signal "L7GND")
		(2 "B.Cu" signal "BOTTOM")
		(9 "F.Adhes" user "F.Adhesive")
		(11 "B.Adhes" user "B.Adhesive")
		(13 "F.Paste" user "Package Geometry/Pastemask Top")
		(15 "B.Paste" user "Package Geometry/Pastemask Bottom")
		(5 "F.SilkS" user "Ref Des/Silkscreen Top")
		(7 "B.SilkS" user "Ref Des/Silkscreen Bottom")
		(1 "F.Mask" user "Board Geometry/Soldermask Top")
		(3 "B.Mask" user "Board Geometry/Soldermask Bottom")
		(17 "Dwgs.User" user "User.Drawings")
		(19 "Cmts.User" user "User.Comments")
		(21 "Eco1.User" user "User.Eco1")
		(23 "Eco2.User" user "User.Eco2")
		(25 "Edge.Cuts" user "Board Geometry/Outline")
		(27 "Margin" user)
		(31 "F.CrtYd" user "Package Geometry/Place Bound Top")
		(29 "B.CrtYd" user "Package Geometry/Place Bound Bottom")
		(35 "F.Fab" user "Ref Des/Assembly Top")
		(33 "B.Fab" user "Ref Des/Assembly Bottom")
	)
	(footprint ""
		(layer "B.Cu")
		(at 21.6916 -67.2084)
		(property "Reference" "C626"
			(at 0 0 0)
			(layer "B.SilkS")
			(hide yes)
			(effects
				(font
					(size 1.27 1.27)
				)
				(justify mirror)
			)
		)
		(property "Value" "SC10U6D3V5KX-4GP"
			(at 0.0762 -6.1214 0)
			(unlocked yes)
			(layer "B.Fab")
			(hide yes)
			(effects
				(font
					(size 1.016 1.016)
					(thickness 0.1524)
				)
				(justify mirror)
			)
		)
		(property "Device Type" "C805H58"
			(at 0.0762 -8.1534 0)
			(unlocked yes)
			(layer "B.Fab")
			(hide yes)
			(effects
				(font
					(size 1.016 1.016)
					(thickness 0.1524)
				)
				(justify mirror)
			)
		)
		(duplicate_pad_numbers_are_jumpers no)
		(fp_line
			(start -0.635 0)
			(end 0.635 0)
			(stroke
				(width 0.508)
				(type default)
			)
			(layer "B.SilkS")
		)
		(fp_rect
			(start 0.9652 1.778)
			(end -0.9652 -1.778)
			(stroke
				(width 0)
				(type default)
			)
			(fill no)
			(layer "B.CrtYd")
		)
		(fp_poly
			(pts
				(xy 0.9652 -1.778) (xy -0.9652 -1.778) (xy -0.9652 1.778) (xy 0.9652 1.778)
			)
			(stroke
				(width 0)
				(type default)
			)
			(fill no)
			(layer "B.Fab")
		)
		(pad "1" smd rect
			(at 0 -0.9652 180)
			(size 1.397 1.143)
			(layers "B.Cu" "B.Mask" "B.Paste")
			(net "P3V3_STBY")
		)
		(pad "2" smd rect
			(at 0 0.9652 180)
			(size 1.397 1.143)
			(layers "B.Cu" "B.Mask" "B.Paste")
			(net "GND")
		)
	)
	(footprint ""
		(layer "B.Cu")
		(at 36.83 -116.84 180)
		(property "Reference" "R283"
			(at 0 0 0)
			(layer "B.SilkS")
			(hide yes)
			(effects
				(font
					(size 1.27 1.27)
				)
				(justify mirror)
			)
		)
		(property "Value" "22R2J-2-GP"
			(at -0.064008 -3.993896 180)
			(unlocked yes)
			(layer "B.Fab")
			(hide yes)
			(effects
				(font
					(size 1.016 1.016)
					(thickness 0.1524)
				)
				(justify mirror)
			)
		)
		(property "Device Type" "R402H16"
			(at -0.064008 -5.517896 180)
			(unlocked yes)
			(layer "B.Fab")
			(hide yes)
			(effects
				(font
					(size 1.016 1.016)
					(thickness 0.1524)
				)
				(justify mirror)
			)
		)
		(duplicate_pad_numbers_are_jumpers no)
		(fp_line
			(start 0.508 -0.9398)
			(end 0.508 0.9398)
			(stroke
				(width 0.1524)
				(type default)
			)
			(layer "B.SilkS")
		)
		(fp_line
			(start -0.508 -0.9398)
			(end 0.508 -0.9398)
			(stroke
				(width 0.1524)
				(type default)
			)
			(layer "B.SilkS")
		)
		(fp_rect
			(start 0.508 0.9398)
			(end -0.508 -0.9398)
			(stroke
				(width 0)
				(type default)
			)
			(fill no)
			(layer "B.CrtYd")
		)
		(fp_rect
			(start 0.508 0.9398)
			(end -0.508 -0.9398)
			(stroke
				(width 0)
				(type default)
			)
			(fill no)
			(layer "B.Fab")
		)
		(pad "1" smd custom
			(at 0 -0.4445)
			(size 0.1397 0.1397)
			(layers "B.Cu" "B.Mask" "B.Paste")
			(net "RMII_BMC_PHY_TXD0")
			(options
				(clearance outline)
				(anchor circle)
			)
			(primitives
				(gr_poly
					(pts
						(arc
							(start -0.1778 0.2794)
							(mid -0.249642 0.249642)
							(end -0.2794 0.1778)
						)
						(arc
							(start -0.2794 -0.1778)
							(mid -0.249642 -0.249642)
							(end -0.1778 -0.2794)
						)
						(arc
							(start 0.1778 -0.2794)
							(mid 0.249642 -0.249642)
							(end 0.2794 -0.1778)
						)
						(arc
							(start 0.2794 0.1778)
							(mid 0.249642 0.249642)
							(end 0.1778 0.2794)
						)
					)
					(width 0)
					(fill yes)
				)
			)
		)
		(pad "2" smd custom
			(at 0 0.4445)
			(size 0.1397 0.1397)
			(layers "B.Cu" "B.Mask" "B.Paste")
			(net "RMII0_BMC_C_PHY_TXD0")
			(options
				(clearance outline)
				(anchor circle)
			)
			(primitives
				(gr_poly
					(pts
						(arc
							(start -0.1778 0.2794)
							(mid -0.249642 0.249642)
							(end -0.2794 0.1778)
						)
						(arc
							(start -0.2794 -0.1778)
							(mid -0.249642 -0.249642)
							(end -0.1778 -0.2794)
						)
						(arc
							(start 0.1778 -0.2794)
							(mid 0.249642 -0.249642)
							(end 0.2794 -0.1778)
						)
						(arc
							(start 0.2794 0.1778)
							(mid 0.249642 0.249642)
							(end 0.1778 0.2794)
						)
					)
					(width 0)
					(fill yes)
				)
			)
		)
	)
	(footprint ""
		(layer "B.Cu")
		(at 237.617 -56.00192 -90)
		(property "Reference" "C522"
			(at 0 0 90)
			(layer "B.SilkS")
			(hide yes)
			(effects
				(font
					(size 1.27 1.27)
				)
				(justify mirror)
			)
		)
		(property "Value" "SCD1U16V1KX-1-GP"
			(at 2.8321 -1.7399 270)
			(unlocked yes)
			(layer "B.Fab")
			(hide yes)
			(effects
				(font
					(size 1.016 1.016)
					(thickness 0.1524)
				)
				(justify mirror)
			)
		)
		(property "Device Type" "C0201H13"
			(at 2.8321 -3.2639 270)
			(unlocked yes)
			(layer "B.Fab")
			(hide yes)
			(effects
				(font
					(size 1.016 1.016)
					(thickness 0.1524)
				)
				(justify mirror)
			)
		)
		(duplicate_pad_numbers_are_jumpers no)
		(fp_rect
			(start 0.2794 0.6477)
			(end -0.2794 -0.6477)
			(stroke
				(width 0)
				(type default)
			)
			(fill no)
			(layer "B.CrtYd")
		)
		(fp_rect
			(start 0.2794 0.6477)
			(end -0.2794 -0.6477)
			(stroke
				(width 0)
				(type default)
			)
			(fill no)
			(layer "B.Fab")
		)
		(pad "1" smd custom
			(at 0 -0.2794 90)
			(size 0.0762 0.0762)
			(layers "B.Cu" "B.Mask" "B.Paste")
			(net "DUT_AVD_TX")
			(options
				(clearance outline)
				(anchor circle)
			)
			(primitives
				(gr_poly
					(pts
						(arc
							(start 0.1524 0.127)
							(mid 0.137521 0.162921)
							(end 0.1016 0.1778)
						)
						(arc
							(start -0.1016 0.1778)
							(mid -0.137521 0.162921)
							(end -0.1524 0.127)
						)
						(arc
							(start -0.1524 -0.127)
							(mid -0.137521 -0.162921)
							(end -0.1016 -0.1778)
						)
						(arc
							(start 0.1016 -0.1778)
							(mid 0.137521 -0.162921)
							(end 0.1524 -0.127)
						)
					)
					(width 0)
					(fill yes)
				)
			)
		)
		(pad "2" smd custom
			(at 0 0.2794 90)
			(size 0.0762 0.0762)
			(layers "B.Cu" "B.Mask" "B.Paste")
			(net "GND")
			(options
				(clearance outline)
				(anchor circle)
			)
			(primitives
				(gr_poly
					(pts
						(arc
							(start 0.1524 0.127)
							(mid 0.137521 0.162921)
							(end 0.1016 0.1778)
						)
						(arc
							(start -0.1016 0.1778)
							(mid -0.137521 0.162921)
							(end -0.1524 0.127)
						)
						(arc
							(start -0.1524 -0.127)
							(mid -0.137521 -0.162921)
							(end -0.1016 -0.1778)
						)
						(arc
							(start 0.1016 -0.1778)
							(mid 0.137521 -0.162921)
							(end 0.1524 -0.127)
						)
					)
					(width 0)
					(fill yes)
				)
			)
		)
	)
	(footprint ""
		(layer "B.Cu")
		(at 29.4894 -73.1774 -90)
		(property "Reference" "PR64"
			(at 0 0 90)
			(layer "B.SilkS")
			(hide yes)
			(effects
				(font
					(size 1.27 1.27)
				)
				(justify mirror)
			)
		)
		(property "Value" "47KR2F-GP"
			(at -0.064008 -3.993896 270)
			(unlocked yes)
			(layer "B.Fab")
			(hide yes)
			(effects
				(font
					(size 1.016 1.016)
					(thickness 0.1524)
				)
				(justify mirror)
			)
		)
		(property "Device Type" "R402H16"
			(at -0.064008 -5.517896 270)
			(unlocked yes)
			(layer "B.Fab")
			(hide yes)
			(effects
				(font
					(size 1.016 1.016)
					(thickness 0.1524)
				)
				(justify mirror)
			)
		)
		(duplicate_pad_numbers_are_jumpers no)
		(fp_line
			(start -0.508 -0.9398)
			(end 0.508 -0.9398)
			(stroke
				(width 0.1524)
				(type default)
			)
			(layer "B.SilkS")
		)
		(fp_line
			(start 0.508 -0.9398)
			(end 0.508 0.9398)
			(stroke
				(width 0.1524)
				(type default)
			)
			(layer "B.SilkS")
		)
		(fp_rect
			(start 0.508 0.9398)
			(end -0.508 -0.9398)
			(stroke
				(width 0)
				(type default)
			)
			(fill no)
			(layer "B.CrtYd")
		)
		(fp_rect
			(start 0.508 0.9398)
			(end -0.508 -0.9398)
			(stroke
				(width 0)
				(type default)
			)
			(fill no)
			(layer "B.Fab")
		)
		(pad "1" smd custom
			(at 0 -0.4445 90)
			(size 0.1397 0.1397)
			(layers "B.Cu" "B.Mask" "B.Paste")
			(net "P12V")
			(options
				(clearance outline)
				(anchor circle)
			)
			(primitives
				(gr_poly
					(pts
						(arc
							(start -0.1778 0.2794)
							(mid -0.249642 0.249642)
							(end -0.2794 0.1778)
						)
						(arc
							(start -0.2794 -0.1778)
							(mid -0.249642 -0.249642)
							(end -0.1778 -0.2794)
						)
						(arc
							(start 0.1778 -0.2794)
							(mid 0.249642 -0.249642)
							(end 0.2794 -0.1778)
						)
						(arc
							(start 0.2794 0.1778)
							(mid 0.249642 0.249642)
							(end 0.1778 0.2794)
						)
					)
					(width 0)
					(fill yes)
				)
			)
		)
		(pad "2" smd custom
			(at 0 0.4445 90)
			(size 0.1397 0.1397)
			(layers "B.Cu" "B.Mask" "B.Paste")
			(net "P5V_STBY_EN")
			(options
				(clearance outline)
				(anchor circle)
			)
			(primitives
				(gr_poly
					(pts
						(arc
							(start -0.1778 0.2794)
							(mid -0.249642 0.249642)
							(end -0.2794 0.1778)
						)
						(arc
							(start -0.2794 -0.1778)
							(mid -0.249642 -0.249642)
							(end -0.1778 -0.2794)
						)
						(arc
							(start 0.1778 -0.2794)
							(mid 0.249642 -0.249642)
							(end 0.2794 -0.1778)
						)
						(arc
							(start 0.2794 0.1778)
							(mid 0.249642 0.249642)
							(end 0.1778 0.2794)
						)
					)
					(width 0)
					(fill yes)
				)
			)
		)
	)
	(footprint ""
		(layer "B.Cu")
		(at 81.706212 -192.641474)
		(property "Reference" "R3232"
			(at 0 0 0)
			(layer "B.SilkS")
			(hide yes)
			(effects
				(font
					(size 1.27 1.27)
				)
				(justify mirror)
			)
		)
		(property "Value" "0R2J-2-GP"
			(at -0.064008 -3.993896 0)
			(unlocked yes)
			(layer "B.Fab")
			(hide yes)
			(effects
				(font
					(size 1.016 1.016)
					(thickness 0.1524)
				)
				(justify mirror)
			)
		)
		(property "Device Type" "R402H16"
			(at -0.064008 -5.517896 0)
			(unlocked yes)
			(layer "B.Fab")
			(hide yes)
			(effects
				(font
					(size 1.016 1.016)
					(thickness 0.1524)
				)
				(justify mirror)
			)
		)
		(duplicate_pad_numbers_are_jumpers no)
		(fp_line
			(start -0.508 -0.9398)
			(end 0.508 -0.9398)
			(stroke
				(width 0.1524)
				(type default)
			)
			(layer "B.SilkS")
		)
		(fp_line
			(start 0.508 -0.9398)
			(end 0.508 0.9398)
			(stroke
				(width 0.1524)
				(type default)
			)
			(layer "B.SilkS")
		)
		(fp_rect
			(start 0.508 0.9398)
			(end -0.508 -0.9398)
			(stroke
				(width 0)
				(type default)
			)
			(fill no)
			(layer "B.CrtYd")
		)
		(fp_rect
			(start 0.508 0.9398)
			(end -0.508 -0.9398)
			(stroke
				(width 0)
				(type default)
			)
			(fill no)
			(layer "B.Fab")
		)
		(pad "1" smd custom
			(at 0 -0.4445 180)
			(size 0.1397 0.1397)
			(layers "B.Cu" "B.Mask" "B.Paste")
			(net "BMC_SSD_RST#10")
			(options
				(clearance outline)
				(anchor circle)
			)
			(primitives
				(gr_poly
					(pts
						(arc
							(start -0.1778 0.2794)
							(mid -0.249642 0.249642)
							(end -0.2794 0.1778)
						)
						(arc
							(start -0.2794 -0.1778)
							(mid -0.249642 -0.249642)
							(end -0.1778 -0.2794)
						)
						(arc
							(start 0.1778 -0.2794)
							(mid 0.249642 -0.249642)
							(end 0.2794 -0.1778)
						)
						(arc
							(start 0.2794 0.1778)
							(mid 0.249642 0.249642)
							(end 0.1778 0.2794)
						)
					)
					(width 0)
					(fill yes)
				)
			)
		)
		(pad "2" smd custom
			(at 0 0.4445 180)
			(size 0.1397 0.1397)
			(layers "B.Cu" "B.Mask" "B.Paste")
			(net "BMC_SSD_RST#0_A10")
			(options
				(clearance outline)
				(anchor circle)
			)
			(primitives
				(gr_poly
					(pts
						(arc
							(start -0.1778 0.2794)
							(mid -0.249642 0.249642)
							(end -0.2794 0.1778)
						)
						(arc
							(start -0.2794 -0.1778)
							(mid -0.249642 -0.249642)
							(end -0.1778 -0.2794)
						)
						(arc
							(start 0.1778 -0.2794)
							(mid 0.249642 -0.249642)
							(end 0.2794 -0.1778)
						)
						(arc
							(start 0.2794 0.1778)
							(mid 0.249642 0.249642)
							(end 0.1778 0.2794)
						)
					)
					(width 0)
					(fill yes)
				)
			)
		)
	)
	(footprint ""
		(layer "B.Cu")
		(at 165.227 -33.528)
		(property "Reference" "R2929"
			(at 0 0 0)
			(layer "B.SilkS")
			(hide yes)
			(effects
				(font
					(size 1.27 1.27)
				)
				(justify mirror)
			)
		)
		(property "Value" "0R2J-2-GP"
			(at -0.064008 -3.993896 0)
			(unlocked yes)
			(layer "B.Fab")
			(hide yes)
			(effects
				(font
					(size 1.016 1.016)
					(thickness 0.1524)
				)
				(justify mirror)
			)
		)
		(property "Device Type" "R402H16"
			(at -0.064008 -5.517896 0)
			(unlocked yes)
			(layer "B.Fab")
			(hide yes)
			(effects
				(font
					(size 1.016 1.016)
					(thickness 0.1524)
				)
				(justify mirror)
			)
		)
		(duplicate_pad_numbers_are_jumpers no)
		(fp_line
			(start -0.508 -0.9398)
			(end 0.508 -0.9398)
			(stroke
				(width 0.1524)
				(type default)
			)
			(layer "B.SilkS")
		)
		(fp_line
			(start 0.508 -0.9398)
			(end 0.508 0.9398)
			(stroke
				(width 0.1524)
				(type default)
			)
			(layer "B.SilkS")
		)
		(fp_rect
			(start 0.508 0.9398)
			(end -0.508 -0.9398)
			(stroke
				(width 0)
				(type default)
			)
			(fill no)
			(layer "B.CrtYd")
		)
		(fp_rect
			(start 0.508 0.9398)
			(end -0.508 -0.9398)
			(stroke
				(width 0)
				(type default)
			)
			(fill no)
			(layer "B.Fab")
		)
		(pad "1" smd custom
			(at 0 -0.4445 180)
			(size 0.1397 0.1397)
			(layers "B.Cu" "B.Mask" "B.Paste")
			(net "CBL_PRSNT_N_4")
			(options
				(clearance outline)
				(anchor circle)
			)
			(primitives
				(gr_poly
					(pts
						(arc
							(start -0.1778 0.2794)
							(mid -0.249642 0.249642)
							(end -0.2794 0.1778)
						)
						(arc
							(start -0.2794 -0.1778)
							(mid -0.249642 -0.249642)
							(end -0.1778 -0.2794)
						)
						(arc
							(start 0.1778 -0.2794)
							(mid 0.249642 -0.249642)
							(end 0.2794 -0.1778)
						)
						(arc
							(start 0.2794 0.1778)
							(mid 0.249642 0.249642)
							(end 0.1778 0.2794)
						)
					)
					(width 0)
					(fill yes)
				)
			)
		)
		(pad "2" smd custom
			(at 0 0.4445 180)
			(size 0.1397 0.1397)
			(layers "B.Cu" "B.Mask" "B.Paste")
			(net "8644_SDA_R_4")
			(options
				(clearance outline)
				(anchor circle)
			)
			(primitives
				(gr_poly
					(pts
						(arc
							(start -0.1778 0.2794)
							(mid -0.249642 0.249642)
							(end -0.2794 0.1778)
						)
						(arc
							(start -0.2794 -0.1778)
							(mid -0.249642 -0.249642)
							(end -0.1778 -0.2794)
						)
						(arc
							(start 0.1778 -0.2794)
							(mid 0.249642 -0.249642)
							(end 0.2794 -0.1778)
						)
						(arc
							(start 0.2794 0.1778)
							(mid 0.249642 0.249642)
							(end 0.1778 0.2794)
						)
					)
					(width 0)
					(fill yes)
				)
			)
		)
	)
	(footprint ""
		(layer "B.Cu")
		(at 263.656318 -3.73634 90)
		(property "Reference" "C153"
			(at 0 0 90)
			(layer "B.SilkS")
			(hide yes)
			(effects
				(font
					(size 1.27 1.27)
				)
				(justify mirror)
			)
		)
		(property "Value" "SC100P50V2JN-3GP"
			(at -1.1811 -2.7051 90)
			(unlocked yes)
			(layer "B.Fab")
			(hide yes)
			(effects
				(font
					(size 1.016 1.016)
					(thickness 0.1524)
				)
				(justify mirror)
			)
		)
		(property "Device Type" "C402H22"
			(at -1.1811 -4.2291 90)
			(unlocked yes)
			(layer "B.Fab")
			(hide yes)
			(effects
				(font
					(size 1.016 1.016)
					(thickness 0.1524)
				)
				(justify mirror)
			)
		)
		(duplicate_pad_numbers_are_jumpers no)
		(fp_rect
			(start 0.4318 0.9525)
			(end -0.4318 -0.9525)
			(stroke
				(width 0)
				(type default)
			)
			(fill no)
			(layer "B.CrtYd")
		)
		(fp_rect
			(start 0.4318 0.9525)
			(end -0.4318 -0.9525)
			(stroke
				(width 0)
				(type default)
			)
			(fill no)
			(layer "B.Fab")
		)
		(pad "1" smd custom
			(at 0 -0.4445 270)
			(size 0.1524 0.1524)
			(layers "B.Cu" "B.Mask" "B.Paste")
			(net "TEMP_SENSOR_DXP")
			(options
				(clearance outline)
				(anchor circle)
			)
			(primitives
				(gr_poly
					(pts
						(arc
							(start 0.3048 0.2032)
							(mid 0.275042 0.275042)
							(end 0.2032 0.3048)
						)
						(arc
							(start -0.2032 0.3048)
							(mid -0.275042 0.275042)
							(end -0.3048 0.2032)
						)
						(arc
							(start -0.3048 -0.2032)
							(mid -0.275042 -0.275042)
							(end -0.2032 -0.3048)
						)
						(arc
							(start 0.2032 -0.3048)
							(mid 0.275042 -0.275042)
							(end 0.3048 -0.2032)
						)
					)
					(width 0)
					(fill yes)
				)
			)
		)
		(pad "2" smd custom
			(at 0 0.4445 270)
			(size 0.1524 0.1524)
			(layers "B.Cu" "B.Mask" "B.Paste")
			(net "TEMP_SENSOR_DXN")
			(options
				(clearance outline)
				(anchor circle)
			)
			(primitives
				(gr_poly
					(pts
						(arc
							(start 0.3048 0.2032)
							(mid 0.275042 0.275042)
							(end 0.2032 0.3048)
						)
						(arc
							(start -0.2032 0.3048)
							(mid -0.275042 0.275042)
							(end -0.3048 0.2032)
						)
						(arc
							(start -0.3048 -0.2032)
							(mid -0.275042 -0.275042)
							(end -0.2032 -0.3048)
						)
						(arc
							(start 0.2032 -0.3048)
							(mid 0.275042 -0.275042)
							(end 0.3048 -0.2032)
						)
					)
					(width 0)
					(fill yes)
				)
			)
		)
	)
)
